(kicad_pcb
	(version 20260206)
	(generator "pcbnew")
	(generator_version "10.0")
	(general
		(thickness 1.6)
		(legacy_teardrops no)
	)
	(paper "A4")
	(title_block
		(title "04192023_DAF0TMB3IC0_F0TG_MB_C_brd_V02_OCP.brd")
		(comment 1 "Grand Teton / footprints 4390-4397 of 8354")
	)
	(layers
		(0 "F.Cu" signal "TOP")
		(4 "In1.Cu" signal "GND")
		(6 "In2.Cu" signal "IN1")
		(8 "In3.Cu" signal "GND1")
		(10 "In4.Cu" signal "IN2")
		(12 "In5.Cu" signal "GND2")
		(14 "In6.Cu" signal "IN3")
		(16 "In7.Cu" signal "GND3")
		(18 "In8.Cu" signal "VCC")
		(20 "In9.Cu" signal "VCC1")
		(22 "In10.Cu" signal "GND4")
		(24 "In11.Cu" signal "IN4")
		(26 "In12.Cu" signal "GND5")
		(28 "In13.Cu" signal "IN5")
		(30 "In14.Cu" signal "GND6")
		(32 "In15.Cu" signal "IN6")
		(34 "In16.Cu" signal "GND7")
		(2 "B.Cu" signal "BOTTOM")
		(9 "F.Adhes" user "F.Adhesive")
		(11 "B.Adhes" user "B.Adhesive")
		(13 "F.Paste" user "Package Geometry/Pastemask Top")
		(15 "B.Paste" user "Package Geometry/Pastemask Bottom")
		(5 "F.SilkS" user "Ref Des/Silkscreen Top")
		(7 "B.SilkS" user "Ref Des/Silkscreen Bottom")
		(1 "F.Mask" user "Board Geometry/Soldermask Top")
		(3 "B.Mask" user "Board Geometry/Soldermask Bottom")
		(17 "Dwgs.User" user "User.Drawings")
		(19 "Cmts.User" user "User.Comments")
		(21 "Eco1.User" user "User.Eco1")
		(23 "Eco2.User" user "User.Eco2")
		(25 "Edge.Cuts" user "Board Geometry/Outline")
		(27 "Margin" user)
		(31 "F.CrtYd" user "Package Geometry/Place Bound Top")
		(29 "B.CrtYd" user "Package Geometry/Place Bound Bottom")
		(35 "F.Fab" user "Ref Des/Assembly Top")
		(33 "B.Fab" user "Ref Des/Assembly Bottom")
	)
	(footprint ""
		(layer "F.Cu")
		(at 243.961158 -380.66853)
		(property "Reference" "PR2535"
			(at 0 0 0)
			(layer "F.SilkS")
			(hide yes)
			(effects
				(font
					(size 1.27 1.27)
				)
			)
		)
		(property "Value" ""
			(at 0 0 0)
			(layer "F.Fab")
			(effects
				(font
					(size 1.27 1.27)
				)
			)
		)
		(duplicate_pad_numbers_are_jumpers no)
		(fp_line
			(start -0.7874 -0.4064)
			(end 0.7874 -0.4064)
			(stroke
				(width 0.1524)
				(type default)
			)
			(layer "F.SilkS")
		)
		(fp_line
			(start -0.7874 0.4064)
			(end -0.7874 -0.4064)
			(stroke
				(width 0.1524)
				(type default)
			)
			(layer "F.SilkS")
		)
		(fp_line
			(start 0.7874 -0.4064)
			(end 0.7874 0.4064)
			(stroke
				(width 0.1524)
				(type default)
			)
			(layer "F.SilkS")
		)
		(fp_line
			(start 0.7874 0.4064)
			(end -0.7874 0.4064)
			(stroke
				(width 0.1524)
				(type default)
			)
			(layer "F.SilkS")
		)
		(fp_line
			(start -0.67945 -0.305054)
			(end -0.12065 -0.305054)
			(stroke
				(width 0.1)
				(type default)
			)
			(layer "F.Fab")
		)
		(fp_line
			(start -0.67945 0.3048)
			(end -0.67945 -0.305054)
			(stroke
				(width 0.1)
				(type default)
			)
			(layer "F.Fab")
		)
		(fp_line
			(start -0.12065 -0.305054)
			(end -0.12065 -0.2794)
			(stroke
				(width 0.1)
				(type default)
			)
			(layer "F.Fab")
		)
		(fp_line
			(start -0.12065 -0.2794)
			(end 0.12065 -0.2794)
			(stroke
				(width 0.1)
				(type default)
			)
			(layer "F.Fab")
		)
		(fp_line
			(start -0.12065 0.2794)
			(end -0.12065 0.3048)
			(stroke
				(width 0.1)
				(type default)
			)
			(layer "F.Fab")
		)
		(fp_line
			(start -0.12065 0.3048)
			(end -0.67945 0.3048)
			(stroke
				(width 0.1)
				(type default)
			)
			(layer "F.Fab")
		)
		(fp_line
			(start 0.120396 0.2794)
			(end -0.12065 0.2794)
			(stroke
				(width 0.1)
				(type default)
			)
			(layer "F.Fab")
		)
		(fp_line
			(start 0.120396 0.3048)
			(end 0.120396 0.2794)
			(stroke
				(width 0.1)
				(type default)
			)
			(layer "F.Fab")
		)
		(fp_line
			(start 0.12065 -0.3048)
			(end 0.67945 -0.3048)
			(stroke
				(width 0.1)
				(type default)
			)
			(layer "F.Fab")
		)
		(fp_line
			(start 0.12065 -0.2794)
			(end 0.12065 -0.3048)
			(stroke
				(width 0.1)
				(type default)
			)
			(layer "F.Fab")
		)
		(fp_line
			(start 0.67945 -0.3048)
			(end 0.67945 0.3048)
			(stroke
				(width 0.1)
				(type default)
			)
			(layer "F.Fab")
		)
		(fp_line
			(start 0.67945 0.3048)
			(end 0.120396 0.3048)
			(stroke
				(width 0.1)
				(type default)
			)
			(layer "F.Fab")
		)
		(pad "1" smd circle
			(at -0.40005 0)
			(size 0 0)
			(layers "F.Cu" "F.Mask" "F.Paste")
			(net "P12V_HSC_GATE_G5")
		)
		(pad "2" smd circle
			(at 0.40005 0)
			(size 0 0)
			(layers "F.Cu" "F.Mask" "F.Paste")
			(net "P12V_HSC_GATE2")
		)
	)
	(footprint ""
		(layer "F.Cu")
		(at 299.265594 -392.1252)
		(property "Reference" "R995"
			(at 0 0 0)
			(layer "F.SilkS")
			(hide yes)
			(effects
				(font
					(size 1.27 1.27)
				)
			)
		)
		(property "Value" ""
			(at 0 0 0)
			(layer "F.Fab")
			(effects
				(font
					(size 1.27 1.27)
				)
			)
		)
		(duplicate_pad_numbers_are_jumpers no)
		(fp_line
			(start -0.32512 -0.175006)
			(end 0.32512 -0.175006)
			(stroke
				(width 0.1)
				(type default)
			)
			(layer "F.Fab")
		)
		(fp_line
			(start -0.32512 0.175006)
			(end -0.32512 -0.175006)
			(stroke
				(width 0.1)
				(type default)
			)
			(layer "F.Fab")
		)
		(fp_line
			(start 0.32512 -0.175006)
			(end 0.32512 0.175006)
			(stroke
				(width 0.1)
				(type default)
			)
			(layer "F.Fab")
		)
		(fp_line
			(start 0.32512 0.175006)
			(end -0.32512 0.175006)
			(stroke
				(width 0.1)
				(type default)
			)
			(layer "F.Fab")
		)
		(pad "1" smd rect
			(at -0.2667 0)
			(size 0.3048 0.381)
			(layers "F.Cu" "F.Mask" "F.Paste")
			(net "TEST2_RT_CPU0_P0")
		)
		(pad "2" smd rect
			(at 0.2667 0 180)
			(size 0.3048 0.381)
			(layers "F.Cu" "F.Mask" "F.Paste")
			(net "GND")
		)
	)
	(footprint ""
		(layer "F.Cu")
		(at 100.442522 -410.672788)
		(property "Reference" "L2"
			(at 0 0 0)
			(layer "F.SilkS")
			(hide yes)
			(effects
				(font
					(size 1.27 1.27)
				)
			)
		)
		(property "Value" ""
			(at 0 0 0)
			(layer "F.Fab")
			(effects
				(font
					(size 1.27 1.27)
				)
			)
		)
		(duplicate_pad_numbers_are_jumpers no)
		(fp_line
			(start -1.63576 -0.8128)
			(end -1.63576 0.8128)
			(stroke
				(width 0.1524)
				(type default)
			)
			(layer "F.SilkS")
		)
		(fp_line
			(start -1.63576 -0.8128)
			(end 1.63576 -0.8128)
			(stroke
				(width 0.1524)
				(type default)
			)
			(layer "F.SilkS")
		)
		(fp_line
			(start 1.63576 -0.8128)
			(end 1.63576 0.8128)
			(stroke
				(width 0.1524)
				(type default)
			)
			(layer "F.SilkS")
		)
		(fp_line
			(start 1.63576 0.8128)
			(end -1.63576 0.8128)
			(stroke
				(width 0.1524)
				(type default)
			)
			(layer "F.SilkS")
		)
		(fp_line
			(start -1.56083 -0.738632)
			(end -1.56083 0.7366)
			(stroke
				(width 0.1)
				(type default)
			)
			(layer "F.Fab")
		)
		(fp_line
			(start -1.56083 0.7366)
			(end -1.524 0.7366)
			(stroke
				(width 0.1)
				(type default)
			)
			(layer "F.Fab")
		)
		(fp_line
			(start -1.524 0.7366)
			(end 1.524 0.7366)
			(stroke
				(width 0.1)
				(type default)
			)
			(layer "F.Fab")
		)
		(fp_line
			(start 1.524 0.7366)
			(end 1.560576 0.7366)
			(stroke
				(width 0.1)
				(type default)
			)
			(layer "F.Fab")
		)
		(fp_line
			(start 1.560576 -0.738632)
			(end -1.56083 -0.738632)
			(stroke
				(width 0.1)
				(type default)
			)
			(layer "F.Fab")
		)
		(fp_line
			(start 1.560576 0.7366)
			(end 1.560576 -0.738632)
			(stroke
				(width 0.1)
				(type default)
			)
			(layer "F.Fab")
		)
		(pad "1" smd rect
			(at -0.94996 0 180)
			(size 1.1176 1.3716)
			(layers "F.Cu" "F.Mask" "F.Paste")
			(net "P3V3_AUX")
		)
		(pad "2" smd rect
			(at 0.94996 0 180)
			(size 1.1176 1.3716)
			(layers "F.Cu" "F.Mask" "F.Paste")
			(net "P3V3_9ZXL045_P1_VDD")
		)
	)
	(footprint ""
		(layer "F.Cu")
		(at 365.835692 -259.355082 180)
		(property "Reference" "C2157"
			(at 0 0 180)
			(layer "F.SilkS")
			(hide yes)
			(effects
				(font
					(size 1.27 1.27)
				)
			)
		)
		(property "Value" ""
			(at 0 0 180)
			(layer "F.Fab")
			(effects
				(font
					(size 1.27 1.27)
				)
			)
		)
		(duplicate_pad_numbers_are_jumpers no)
		(fp_line
			(start 0.7874 0.4064)
			(end -0.7874 0.4064)
			(stroke
				(width 0.1524)
				(type default)
			)
			(layer "F.SilkS")
		)
		(fp_line
			(start 0.7874 -0.4064)
			(end 0.7874 0.4064)
			(stroke
				(width 0.1524)
				(type default)
			)
			(layer "F.SilkS")
		)
		(fp_line
			(start -0.7874 0.4064)
			(end -0.7874 -0.4064)
			(stroke
				(width 0.1524)
				(type default)
			)
			(layer "F.SilkS")
		)
		(fp_line
			(start -0.7874 -0.4064)
			(end 0.7874 -0.4064)
			(stroke
				(width 0.1524)
				(type default)
			)
			(layer "F.SilkS")
		)
		(fp_line
			(start 0.67945 0.3048)
			(end 0.120396 0.3048)
			(stroke
				(width 0.1)
				(type default)
			)
			(layer "F.Fab")
		)
		(fp_line
			(start 0.67945 -0.3048)
			(end 0.67945 0.3048)
			(stroke
				(width 0.1)
				(type default)
			)
			(layer "F.Fab")
		)
		(fp_line
			(start 0.12065 -0.2794)
			(end 0.12065 -0.3048)
			(stroke
				(width 0.1)
				(type default)
			)
			(layer "F.Fab")
		)
		(fp_line
			(start 0.12065 -0.3048)
			(end 0.67945 -0.3048)
			(stroke
				(width 0.1)
				(type default)
			)
			(layer "F.Fab")
		)
		(fp_line
			(start 0.120396 0.3048)
			(end 0.120396 0.2794)
			(stroke
				(width 0.1)
				(type default)
			)
			(layer "F.Fab")
		)
		(fp_line
			(start 0.120396 0.2794)
			(end -0.12065 0.2794)
			(stroke
				(width 0.1)
				(type default)
			)
			(layer "F.Fab")
		)
		(fp_line
			(start -0.12065 0.3048)
			(end -0.67945 0.3048)
			(stroke
				(width 0.1)
				(type default)
			)
			(layer "F.Fab")
		)
		(fp_line
			(start -0.12065 0.2794)
			(end -0.12065 0.3048)
			(stroke
				(width 0.1)
				(type default)
			)
			(layer "F.Fab")
		)
		(fp_line
			(start -0.12065 -0.2794)
			(end 0.12065 -0.2794)
			(stroke
				(width 0.1)
				(type default)
			)
			(layer "F.Fab")
		)
		(fp_line
			(start -0.12065 -0.305054)
			(end -0.12065 -0.2794)
			(stroke
				(width 0.1)
				(type default)
			)
			(layer "F.Fab")
		)
		(fp_line
			(start -0.67945 0.3048)
			(end -0.67945 -0.305054)
			(stroke
				(width 0.1)
				(type default)
			)
			(layer "F.Fab")
		)
		(fp_line
			(start -0.67945 -0.305054)
			(end -0.12065 -0.305054)
			(stroke
				(width 0.1)
				(type default)
			)
			(layer "F.Fab")
		)
		(pad "1" smd circle
			(at -0.40005 0 180)
			(size 0 0)
			(layers "F.Cu" "F.Mask" "F.Paste")
			(net "PVDDCR_SOC_P0")
		)
		(pad "2" smd circle
			(at 0.40005 0 180)
			(size 0 0)
			(layers "F.Cu" "F.Mask" "F.Paste")
			(net "GND")
		)
	)
	(footprint ""
		(layer "F.Cu")
		(at 65.193164 -17.227804 180)
		(property "Reference" "C1829"
			(at 0 0 180)
			(layer "F.SilkS")
			(hide yes)
			(effects
				(font
					(size 1.27 1.27)
				)
			)
		)
		(property "Value" ""
			(at 0 0 180)
			(layer "F.Fab")
			(effects
				(font
					(size 1.27 1.27)
				)
			)
		)
		(duplicate_pad_numbers_are_jumpers no)
		(fp_line
			(start 1.524 0.762)
			(end -1.524 0.762)
			(stroke
				(width 0.1524)
				(type default)
			)
			(layer "F.SilkS")
		)
		(fp_line
			(start 1.524 -0.762)
			(end 1.524 0.762)
			(stroke
				(width 0.1524)
				(type default)
			)
			(layer "F.SilkS")
		)
		(fp_line
			(start -1.524 0.762)
			(end -1.524 -0.762)
			(stroke
				(width 0.1524)
				(type default)
			)
			(layer "F.SilkS")
		)
		(fp_line
			(start -1.524 -0.762)
			(end 1.524 -0.762)
			(stroke
				(width 0.1524)
				(type default)
			)
			(layer "F.SilkS")
		)
		(fp_line
			(start 1.1049 0.724916)
			(end 1.1049 -0.724916)
			(stroke
				(width 0.1)
				(type default)
			)
			(layer "F.Fab")
		)
		(fp_line
			(start 1.1049 -0.724916)
			(end -1.1049 -0.724916)
			(stroke
				(width 0.1)
				(type default)
			)
			(layer "F.Fab")
		)
		(fp_line
			(start -1.1049 0.724916)
			(end 1.1049 0.724916)
			(stroke
				(width 0.1)
				(type default)
			)
			(layer "F.Fab")
		)
		(fp_line
			(start -1.1049 -0.724916)
			(end -1.1049 0.724916)
			(stroke
				(width 0.1)
				(type default)
			)
			(layer "F.Fab")
		)
		(pad "1" smd rect
			(at -0.889 0)
			(size 1.016 1.27)
			(layers "F.Cu" "F.Mask" "F.Paste")
			(net "P12V_OCP_V3_2_R")
		)
		(pad "2" smd rect
			(at 0.889 0)
			(size 1.016 1.27)
			(layers "F.Cu" "F.Mask" "F.Paste")
			(net "GND")
		)
	)
	(footprint ""
		(layer "F.Cu")
		(at 116.158518 -395.340586 -90)
		(property "Reference" "R912"
			(at 0 0 270)
			(layer "F.SilkS")
			(hide yes)
			(effects
				(font
					(size 1.27 1.27)
				)
			)
		)
		(property "Value" ""
			(at 0 0 270)
			(layer "F.Fab")
			(effects
				(font
					(size 1.27 1.27)
				)
			)
		)
		(duplicate_pad_numbers_are_jumpers no)
		(fp_line
			(start -0.32512 0.175006)
			(end -0.32512 -0.175006)
			(stroke
				(width 0.1)
				(type default)
			)
			(layer "F.Fab")
		)
		(fp_line
			(start 0.32512 0.175006)
			(end -0.32512 0.175006)
			(stroke
				(width 0.1)
				(type default)
			)
			(layer "F.Fab")
		)
		(fp_line
			(start -0.32512 -0.175006)
			(end 0.32512 -0.175006)
			(stroke
				(width 0.1)
				(type default)
			)
			(layer "F.Fab")
		)
		(fp_line
			(start 0.32512 -0.175006)
			(end 0.32512 0.175006)
			(stroke
				(width 0.1)
				(type default)
			)
			(layer "F.Fab")
		)
		(pad "1" smd rect
			(at -0.2667 0 270)
			(size 0.3048 0.381)
			(layers "F.Cu" "F.Mask" "F.Paste")
			(net "P1V8_CPU1_RT_1D")
		)
		(pad "2" smd rect
			(at 0.2667 0 90)
			(size 0.3048 0.381)
			(layers "F.Cu" "F.Mask" "F.Paste")
			(net "JTAG_TEST_MODE_RT_CPU1_P3")
		)
	)
	(footprint ""
		(layer "F.Cu")
		(at 120.69826 -31.405576)
		(property "Reference" "R6269"
			(at 0 0 0)
			(layer "F.SilkS")
			(hide yes)
			(effects
				(font
					(size 1.27 1.27)
				)
			)
		)
		(property "Value" ""
			(at 0 0 0)
			(layer "F.Fab")
			(effects
				(font
					(size 1.27 1.27)
				)
			)
		)
		(duplicate_pad_numbers_are_jumpers no)
		(fp_line
			(start -0.7874 -0.4064)
			(end 0.7874 -0.4064)
			(stroke
				(width 0.1524)
				(type default)
			)
			(layer "F.SilkS")
		)
		(fp_line
			(start -0.7874 0.4064)
			(end -0.7874 -0.4064)
			(stroke
				(width 0.1524)
				(type default)
			)
			(layer "F.SilkS")
		)
		(fp_line
			(start 0.7874 -0.4064)
			(end 0.7874 0.4064)
			(stroke
				(width 0.1524)
				(type default)
			)
			(layer "F.SilkS")
		)
		(fp_line
			(start 0.7874 0.4064)
			(end -0.7874 0.4064)
			(stroke
				(width 0.1524)
				(type default)
			)
			(layer "F.SilkS")
		)
		(fp_line
			(start -0.67945 -0.305054)
			(end -0.12065 -0.305054)
			(stroke
				(width 0.1)
				(type default)
			)
			(layer "F.Fab")
		)
		(fp_line
			(start -0.67945 0.3048)
			(end -0.67945 -0.305054)
			(stroke
				(width 0.1)
				(type default)
			)
			(layer "F.Fab")
		)
		(fp_line
			(start -0.12065 -0.305054)
			(end -0.12065 -0.2794)
			(stroke
				(width 0.1)
				(type default)
			)
			(layer "F.Fab")
		)
		(fp_line
			(start -0.12065 -0.2794)
			(end 0.12065 -0.2794)
			(stroke
				(width 0.1)
				(type default)
			)
			(layer "F.Fab")
		)
		(fp_line
			(start -0.12065 0.2794)
			(end -0.12065 0.3048)
			(stroke
				(width 0.1)
				(type default)
			)
			(layer "F.Fab")
		)
		(fp_line
			(start -0.12065 0.3048)
			(end -0.67945 0.3048)
			(stroke
				(width 0.1)
				(type default)
			)
			(layer "F.Fab")
		)
		(fp_line
			(start 0.120396 0.2794)
			(end -0.12065 0.2794)
			(stroke
				(width 0.1)
				(type default)
			)
			(layer "F.Fab")
		)
		(fp_line
			(start 0.120396 0.3048)
			(end 0.120396 0.2794)
			(stroke
				(width 0.1)
				(type default)
			)
			(layer "F.Fab")
		)
		(fp_line
			(start 0.12065 -0.3048)
			(end 0.67945 -0.3048)
			(stroke
				(width 0.1)
				(type default)
			)
			(layer "F.Fab")
		)
		(fp_line
			(start 0.12065 -0.2794)
			(end 0.12065 -0.3048)
			(stroke
				(width 0.1)
				(type default)
			)
			(layer "F.Fab")
		)
		(fp_line
			(start 0.67945 -0.3048)
			(end 0.67945 0.3048)
			(stroke
				(width 0.1)
				(type default)
			)
			(layer "F.Fab")
		)
		(fp_line
			(start 0.67945 0.3048)
			(end 0.120396 0.3048)
			(stroke
				(width 0.1)
				(type default)
			)
			(layer "F.Fab")
		)
		(pad "1" smd circle
			(at -0.40005 0)
			(size 0 0)
			(layers "F.Cu" "F.Mask" "F.Paste")
			(net "USB_HUB2_TI_VDD_MRP_USB3DN_RXDP4")
		)
		(pad "2" smd circle
			(at 0.40005 0)
			(size 0 0)
			(layers "F.Cu" "F.Mask" "F.Paste")
			(net "P1V2_CPU0_USB2_DVDD12")
		)
	)
	(footprint ""
		(layer "F.Cu")
		(at 363.554772 -173.119542 -90)
		(property "Reference" "PR322"
			(at 0 0 270)
			(layer "F.SilkS")
			(hide yes)
			(effects
				(font
					(size 1.27 1.27)
				)
			)
		)
		(property "Value" ""
			(at 0 0 270)
			(layer "F.Fab")
			(effects
				(font
					(size 1.27 1.27)
				)
			)
		)
		(duplicate_pad_numbers_are_jumpers no)
		(fp_line
			(start -0.7874 0.4064)
			(end -0.7874 -0.4064)
			(stroke
				(width 0.1524)
				(type default)
			)
			(layer "F.SilkS")
		)
		(fp_line
			(start 0.7874 0.4064)
			(end -0.7874 0.4064)
			(stroke
				(width 0.1524)
				(type default)
			)
			(layer "F.SilkS")
		)
		(fp_line
			(start -0.7874 -0.4064)
			(end 0.7874 -0.4064)
			(stroke
				(width 0.1524)
				(type default)
			)
			(layer "F.SilkS")
		)
		(fp_line
			(start 0.7874 -0.4064)
			(end 0.7874 0.4064)
			(stroke
				(width 0.1524)
				(type default)
			)
			(layer "F.SilkS")
		)
		(fp_line
			(start -0.67945 0.3048)
			(end -0.67945 -0.305054)
			(stroke
				(width 0.1)
				(type default)
			)
			(layer "F.Fab")
		)
		(fp_line
			(start -0.12065 0.3048)
			(end -0.67945 0.3048)
			(stroke
				(width 0.1)
				(type default)
			)
			(layer "F.Fab")
		)
		(fp_line
			(start 0.120396 0.3048)
			(end 0.120396 0.2794)
			(stroke
				(width 0.1)
				(type default)
			)
			(layer "F.Fab")
		)
		(fp_line
			(start 0.67945 0.3048)
			(end 0.120396 0.3048)
			(stroke
				(width 0.1)
				(type default)
			)
			(layer "F.Fab")
		)
		(fp_line
			(start -0.12065 0.2794)
			(end -0.12065 0.3048)
			(stroke
				(width 0.1)
				(type default)
			)
			(layer "F.Fab")
		)
		(fp_line
			(start 0.120396 0.2794)
			(end -0.12065 0.2794)
			(stroke
				(width 0.1)
				(type default)
			)
			(layer "F.Fab")
		)
		(fp_line
			(start -0.12065 -0.2794)
			(end 0.12065 -0.2794)
			(stroke
				(width 0.1)
				(type default)
			)
			(layer "F.Fab")
		)
		(fp_line
			(start 0.12065 -0.2794)
			(end 0.12065 -0.3048)
			(stroke
				(width 0.1)
				(type default)
			)
			(layer "F.Fab")
		)
		(fp_line
			(start 0.12065 -0.3048)
			(end 0.67945 -0.3048)
			(stroke
				(width 0.1)
				(type default)
			)
			(layer "F.Fab")
		)
		(fp_line
			(start 0.67945 -0.3048)
			(end 0.67945 0.3048)
			(stroke
				(width 0.1)
				(type default)
			)
			(layer "F.Fab")
		)
		(fp_line
			(start -0.67945 -0.305054)
			(end -0.12065 -0.305054)
			(stroke
				(width 0.1)
				(type default)
			)
			(layer "F.Fab")
		)
		(fp_line
			(start -0.12065 -0.305054)
			(end -0.12065 -0.2794)
			(stroke
				(width 0.1)
				(type default)
			)
			(layer "F.Fab")
		)
		(pad "1" smd circle
			(at -0.40005 0 270)
			(size 0 0)
			(layers "F.Cu" "F.Mask" "F.Paste")
			(net "SW_PVDDCR_CPU0_P0_BOOT1")
		)
		(pad "2" smd circle
			(at 0.40005 0 270)
			(size 0 0)
			(layers "F.Cu" "F.Mask" "F.Paste")
			(net "SW_PVDDCR_CPU0_P0_BOOT1_RC")
		)
	)
)
